(kicad_pcb
	(version 20260206)
	(generator "pcbnew")
	(generator_version "10.0")
	(general
		(thickness 1.6)
		(legacy_teardrops no)
	)
	(paper "A4")
	(title_block
		(title "v1-chassis-manager — T6M_CM_d_v01_1031_1645.brd")
		(comment 1 "Open CloudServer (Microsoft) / footprints 1387-1387 of 2512")
	)
	(layers
		(0 "F.Cu" signal "TOP")
		(4 "In1.Cu" signal "GND1")
		(6 "In2.Cu" signal "IN1")
		(8 "In3.Cu" signal "VCC1")
		(10 "In4.Cu" signal "VCC2")
		(12 "In5.Cu" signal "GND2")
		(14 "In6.Cu" signal "IN2")
		(16 "In7.Cu" signal "IN3")
		(18 "In8.Cu" signal "GND3")
		(2 "B.Cu" signal "BOTTOM")
		(9 "F.Adhes" user "F.Adhesive")
		(11 "B.Adhes" user "B.Adhesive")
		(13 "F.Paste" user "Package Geometry/Pastemask Top")
		(15 "B.Paste" user "Package Geometry/Pastemask Bottom")
		(5 "F.SilkS" user "Ref Des/Silkscreen Top")
		(7 "B.SilkS" user "Ref Des/Silkscreen Bottom")
		(1 "F.Mask" user "Board Geometry/Soldermask Top")
		(3 "B.Mask" user "Board Geometry/Soldermask Bottom")
		(17 "Dwgs.User" user "User.Drawings")
		(19 "Cmts.User" user "User.Comments")
		(21 "Eco1.User" user "User.Eco1")
		(23 "Eco2.User" user "User.Eco2")
		(25 "Edge.Cuts" user "Board Geometry/Outline")
		(27 "Margin" user)
		(31 "F.CrtYd" user "Package Geometry/Place Bound Top")
		(29 "B.CrtYd" user "Package Geometry/Place Bound Bottom")
		(35 "F.Fab" user "Ref Des/Assembly Top")
		(33 "B.Fab" user "Ref Des/Assembly Bottom")
	)
	(footprint ""
		(layer "F.Cu")
		(at 163.449 -188.087 -90)
		(property "Reference" "R1334"
			(at -1.1684 -1.55067 90)
			(unlocked yes)
			(layer "F.SilkS")
			(effects
				(font
					(size 0.7874 0.5842)
					(thickness 0.1524)
				)
				(justify left)
			)
		)
		(property "Value" ""
			(at 0 0 270)
			(layer "F.Fab")
			(effects
				(font
					(size 1.27 1.27)
				)
			)
		)
		(duplicate_pad_numbers_are_jumpers no)
		(fp_line
			(start -0.7874 0.4064)
			(end -0.7874 -0.4064)
			(stroke
				(width 0.1524)
				(type default)
			)
			(layer "F.SilkS")
		)
		(fp_line
			(start 0.7874 0.4064)
			(end -0.7874 0.4064)
			(stroke
				(width 0.1524)
				(type default)
			)
			(layer "F.SilkS")
		)
		(fp_line
			(start -0.7874 -0.4064)
			(end 0.7874 -0.4064)
			(stroke
				(width 0.1524)
				(type default)
			)
			(layer "F.SilkS")
		)
		(fp_line
			(start 0.7874 -0.4064)
			(end 0.7874 0.4064)
			(stroke
				(width 0.1524)
				(type default)
			)
			(layer "F.SilkS")
		)
		(fp_poly
			(pts
				(xy -0.508 0.2794) (xy -0.508 0.2286) (xy -0.635 0.2286) (xy -0.635 -0.254) (xy -0.5334 -0.254)
				(xy -0.5334 -0.2794) (xy 0.5334 -0.2794) (xy 0.5334 -0.254) (xy 0.635 -0.254) (xy 0.635 0.254) (xy 0.5334 0.254)
				(xy 0.5334 0.2794)
			)
			(stroke
				(width 0)
				(type default)
			)
			(fill no)
			(layer "F.CrtYd")
		)
		(pad "1" smd rect
			(at 0.40005 0 270)
			(size 0.4572 0.508)
			(layers "F.Cu" "F.Mask" "F.Paste")
			(net "UART_RI_RP5_L_N")
		)
		(pad "2" smd rect
			(at -0.40005 0 270)
			(size 0.4572 0.508)
			(layers "F.Cu" "F.Mask" "F.Paste")
			(net "UART_RI_RP5_L_N_R")
		)
	)
)
